# S9S_MB_2U (Grand Teton) — schematic netlist excerpt (pin names and nets, part order shuffled) for the footprints in the layout excerpt that follows; sources: Cadence DE-HDL packaged netlist, KiCad conversion of 03242023_DA0F0TMBIJ0_F0T_Motherboard_J_brd_V01_OCP.brd

PR3988  Q_RES  0 5% CHIP  pkg 0402LF  page 303 : A = HSC_SCREF ; B = HSC_SCREF_3
C580  Q_CAP  0.1UF 25V 10% X7R  pkg 0402  page 158 : A = P3V3_OCP_SFF ; B = GND

(kicad_pcb
	(version 20260206)
	(generator "pcbnew")
	(generator_version "10.0")
	(general
		(thickness 1.6)
		(legacy_teardrops no)
	)
	(paper "A4")
	(title_block
		(title "03242023_DA0F0TMBIJ0_F0T_Motherboard_J_brd_V01_OCP.brd")
		(comment 1 "Grand Teton / footprints 300-301 of 6105")
	)
	(layers
		(0 "F.Cu" signal "TOP")
		(4 "In1.Cu" signal "GND")
		(6 "In2.Cu" signal "IN1")
		(8 "In3.Cu" signal "GND1")
		(10 "In4.Cu" signal "IN2")
		(12 "In5.Cu" signal "GND2")
		(14 "In6.Cu" signal "IN3")
		(16 "In7.Cu" signal "GND3")
		(18 "In8.Cu" signal "VCC")
		(20 "In9.Cu" signal "VCC1")
		(22 "In10.Cu" signal "GND4")
		(24 "In11.Cu" signal "IN4")
		(26 "In12.Cu" signal "GND5")
		(28 "In13.Cu" signal "IN5")
		(30 "In14.Cu" signal "GND6")
		(32 "In15.Cu" signal "IN6")
		(34 "In16.Cu" signal "GND7")
		(2 "B.Cu" signal "BOTTOM")
		(9 "F.Adhes" user "F.Adhesive")
		(11 "B.Adhes" user "B.Adhesive")
		(13 "F.Paste" user "Package Geometry/Pastemask Top")
		(15 "B.Paste" user "Package Geometry/Pastemask Bottom")
		(5 "F.SilkS" user "Ref Des/Silkscreen Top")
		(7 "B.SilkS" user "Ref Des/Silkscreen Bottom")
		(1 "F.Mask" user "Board Geometry/Soldermask Top")
		(3 "B.Mask" user "Board Geometry/Soldermask Bottom")
		(17 "Dwgs.User" user "User.Drawings")
		(19 "Cmts.User" user "User.Comments")
		(21 "Eco1.User" user "User.Eco1")
		(23 "Eco2.User" user "User.Eco2")
		(25 "Edge.Cuts" user "Board Geometry/Outline")
		(27 "Margin" user)
		(31 "F.CrtYd" user "Package Geometry/Place Bound Top")
		(29 "B.CrtYd" user "Package Geometry/Place Bound Bottom")
		(35 "F.Fab" user "Ref Des/Assembly Top")
		(33 "B.Fab" user "Ref Des/Assembly Bottom")
	)
	(footprint ""
		(layer "F.Cu")
		(at 216.065608 -408.887422)
		(property "Reference" "PR3988"
			(at 0 0 0)
			(layer "F.SilkS")
			(hide yes)
			(effects
				(font
					(size 1.27 1.27)
				)
			)
		)
		(property "Value" ""
			(at 0 0 0)
			(layer "F.Fab")
			(effects
				(font
					(size 1.27 1.27)
				)
			)
		)
		(duplicate_pad_numbers_are_jumpers no)
		(fp_line
			(start -0.7874 -0.4064)
			(end 0.7874 -0.4064)
			(stroke
				(width 0.1524)
				(type default)
			)
			(layer "F.SilkS")
		)
		(fp_line
			(start -0.7874 0.4064)
			(end -0.7874 -0.4064)
			(stroke
				(width 0.1524)
				(type default)
			)
			(layer "F.SilkS")
		)
		(fp_line
			(start 0.7874 -0.4064)
			(end 0.7874 0.4064)
			(stroke
				(width 0.1524)
				(type default)
			)
			(layer "F.SilkS")
		)
		(fp_line
			(start 0.7874 0.4064)
			(end -0.7874 0.4064)
			(stroke
				(width 0.1524)
				(type default)
			)
			(layer "F.SilkS")
		)
		(fp_line
			(start -0.67945 -0.305054)
			(end -0.12065 -0.305054)
			(stroke
				(width 0.1)
				(type default)
			)
			(layer "F.Fab")
		)
		(fp_line
			(start -0.67945 0.3048)
			(end -0.67945 -0.305054)
			(stroke
				(width 0.1)
				(type default)
			)
			(layer "F.Fab")
		)
		(fp_line
			(start -0.12065 -0.305054)
			(end -0.12065 -0.2794)
			(stroke
				(width 0.1)
				(type default)
			)
			(layer "F.Fab")
		)
		(fp_line
			(start -0.12065 -0.2794)
			(end 0.12065 -0.2794)
			(stroke
				(width 0.1)
				(type default)
			)
			(layer "F.Fab")
		)
		(fp_line
			(start -0.12065 0.2794)
			(end -0.12065 0.3048)
			(stroke
				(width 0.1)
				(type default)
			)
			(layer "F.Fab")
		)
		(fp_line
			(start -0.12065 0.3048)
			(end -0.67945 0.3048)
			(stroke
				(width 0.1)
				(type default)
			)
			(layer "F.Fab")
		)
		(fp_line
			(start 0.120396 0.2794)
			(end -0.12065 0.2794)
			(stroke
				(width 0.1)
				(type default)
			)
			(layer "F.Fab")
		)
		(fp_line
			(start 0.120396 0.3048)
			(end 0.120396 0.2794)
			(stroke
				(width 0.1)
				(type default)
			)
			(layer "F.Fab")
		)
		(fp_line
			(start 0.12065 -0.3048)
			(end 0.67945 -0.3048)
			(stroke
				(width 0.1)
				(type default)
			)
			(layer "F.Fab")
		)
		(fp_line
			(start 0.12065 -0.2794)
			(end 0.12065 -0.3048)
			(stroke
				(width 0.1)
				(type default)
			)
			(layer "F.Fab")
		)
		(fp_line
			(start 0.67945 -0.3048)
			(end 0.67945 0.3048)
			(stroke
				(width 0.1)
				(type default)
			)
			(layer "F.Fab")
		)
		(fp_line
			(start 0.67945 0.3048)
			(end 0.120396 0.3048)
			(stroke
				(width 0.1)
				(type default)
			)
			(layer "F.Fab")
		)
		(pad "1" smd circle
			(at -0.40005 0)
			(size 0 0)
			(layers "F.Cu" "F.Mask" "F.Paste")
			(net "HSC_SCREF")
		)
		(pad "2" smd circle
			(at 0.40005 0)
			(size 0 0)
			(layers "F.Cu" "F.Mask" "F.Paste")
			(net "HSC_SCREF_3")
		)
	)
	(footprint ""
		(layer "F.Cu")
		(at 388.025132 -38.265354 180)
		(property "Reference" "C580"
			(at 0 0 180)
			(layer "F.SilkS")
			(hide yes)
			(effects
				(font
					(size 1.27 1.27)
				)
			)
		)
		(property "Value" ""
			(at 0 0 180)
			(layer "F.Fab")
			(effects
				(font
					(size 1.27 1.27)
				)
			)
		)
		(duplicate_pad_numbers_are_jumpers no)
		(fp_line
			(start 0.7874 0.4064)
			(end -0.7874 0.4064)
			(stroke
				(width 0.1524)
				(type default)
			)
			(layer "F.SilkS")
		)
		(fp_line
			(start 0.7874 -0.4064)
			(end 0.7874 0.4064)
			(stroke
				(width 0.1524)
				(type default)
			)
			(layer "F.SilkS")
		)
		(fp_line
			(start -0.7874 0.4064)
			(end -0.7874 -0.4064)
			(stroke
				(width 0.1524)
				(type default)
			)
			(layer "F.SilkS")
		)
		(fp_line
			(start -0.7874 -0.4064)
			(end 0.7874 -0.4064)
			(stroke
				(width 0.1524)
				(type default)
			)
			(layer "F.SilkS")
		)
		(fp_line
			(start 0.67945 0.3048)
			(end 0.120396 0.3048)
			(stroke
				(width 0.1)
				(type default)
			)
			(layer "F.Fab")
		)
		(fp_line
			(start 0.67945 -0.3048)
			(end 0.67945 0.3048)
			(stroke
				(width 0.1)
				(type default)
			)
			(layer "F.Fab")
		)
		(fp_line
			(start 0.12065 -0.2794)
			(end 0.12065 -0.3048)
			(stroke
				(width 0.1)
				(type default)
			)
			(layer "F.Fab")
		)
		(fp_line
			(start 0.12065 -0.3048)
			(end 0.67945 -0.3048)
			(stroke
				(width 0.1)
				(type default)
			)
			(layer "F.Fab")
		)
		(fp_line
			(start 0.120396 0.3048)
			(end 0.120396 0.2794)
			(stroke
				(width 0.1)
				(type default)
			)
			(layer "F.Fab")
		)
		(fp_line
			(start 0.120396 0.2794)
			(end -0.12065 0.2794)
			(stroke
				(width 0.1)
				(type default)
			)
			(layer "F.Fab")
		)
		(fp_line
			(start -0.12065 0.3048)
			(end -0.67945 0.3048)
			(stroke
				(width 0.1)
				(type default)
			)
			(layer "F.Fab")
		)
		(fp_line
			(start -0.12065 0.2794)
			(end -0.12065 0.3048)
			(stroke
				(width 0.1)
				(type default)
			)
			(layer "F.Fab")
		)
		(fp_line
			(start -0.12065 -0.2794)
			(end 0.12065 -0.2794)
			(stroke
				(width 0.1)
				(type default)
			)
			(layer "F.Fab")
		)
		(fp_line
			(start -0.12065 -0.305054)
			(end -0.12065 -0.2794)
			(stroke
				(width 0.1)
				(type default)
			)
			(layer "F.Fab")
		)
		(fp_line
			(start -0.67945 0.3048)
			(end -0.67945 -0.305054)
			(stroke
				(width 0.1)
				(type default)
			)
			(layer "F.Fab")
		)
		(fp_line
			(start -0.67945 -0.305054)
			(end -0.12065 -0.305054)
			(stroke
				(width 0.1)
				(type default)
			)
			(layer "F.Fab")
		)
		(pad "1" smd circle
			(at -0.40005 0 180)
			(size 0 0)
			(layers "F.Cu" "F.Mask" "F.Paste")
			(net "P3V3_OCP_SFF")
		)
		(pad "2" smd circle
			(at 0.40005 0 180)
			(size 0 0)
			(layers "F.Cu" "F.Mask" "F.Paste")
			(net "GND")
		)
	)
)
